(kicad_pcb
	(version 20241229)
	(generator "pcbnew")
	(generator_version "9.0")
	(general
		(thickness 1.62)
		(legacy_teardrops no)
	)
	(paper "A3")
	(title_block
		(title "COM Express 7 Baseboard")
		(date "2025-02-04")
		(rev "1.1.2")
		(company "Antmicro Ltd")
		(comment 1 "www.antmicro.com")
		(comment 9 "footprints 691-696 of 802")
	)
	(layers
		(0 "F.Cu" signal)
		(4 "In1.Cu" signal)
		(6 "In2.Cu" signal)
		(8 "In3.Cu" signal)
		(10 "In4.Cu" signal)
		(12 "In5.Cu" signal)
		(14 "In6.Cu" signal)
		(2 "B.Cu" signal)
		(9 "F.Adhes" user "F.Adhesive")
		(11 "B.Adhes" user "B.Adhesive")
		(13 "F.Paste" user)
		(15 "B.Paste" user)
		(5 "F.SilkS" user "F.Silkscreen")
		(7 "B.SilkS" user "B.Silkscreen")
		(1 "F.Mask" user)
		(3 "B.Mask" user)
		(17 "Dwgs.User" user "User.Drawings")
		(19 "Cmts.User" user "User.Comments")
		(21 "Eco1.User" user "User.Eco1")
		(23 "Eco2.User" user "User.Eco2")
		(25 "Edge.Cuts" user)
		(27 "Margin" user)
		(31 "F.CrtYd" user "F.Courtyard")
		(29 "B.CrtYd" user "B.Courtyard")
		(35 "F.Fab" user)
		(33 "B.Fab" user)
	)
	(footprint "antmicro-footprints:TP_SMD_0.75mm"
		(layer "B.Cu")
		(at 177.35 163.8)
		(property "Reference" "TP22"
			(at -0.35 -2.3 270)
			(layer "B.SilkS")
			(effects
				(font
					(size 0.7 0.7)
					(thickness 0.15)
				)
				(justify right top mirror)
			)
		)
		(property "Value" "TP_0.75mm_SMD"
			(at 3.225 -53.865 0)
			(layer "B.Fab")
			(hide yes)
			(effects
				(font
					(size 0.7 0.7)
					(thickness 0.15)
				)
				(justify right top mirror)
			)
		)
		(property "Author" "Antmicro"
			(at 454.8 308.02 0)
			(layer "B.Fab")
			(hide yes)
			(effects
				(font
					(size 1 1)
					(thickness 0.15)
				)
				(justify mirror)
			)
		)
		(property "License" "Apache-2.0"
			(at 454.8 308.02 0)
			(layer "B.Fab")
			(hide yes)
			(effects
				(font
					(size 1 1)
					(thickness 0.15)
				)
				(justify mirror)
			)
		)
		(property "MPN" ""
			(at 454.8 308.02 0)
			(layer "B.Fab")
			(hide yes)
			(effects
				(font
					(size 1 1)
					(thickness 0.15)
				)
				(justify mirror)
			)
		)
		(property "Manufacturer" ""
			(at 454.8 308.02 0)
			(layer "B.Fab")
			(hide yes)
			(effects
				(font
					(size 1 1)
					(thickness 0.15)
				)
				(justify mirror)
			)
		)
		(property "Public" "False"
			(at 454.8 308.02 0)
			(layer "B.Fab")
			(hide yes)
			(effects
				(font
					(size 1 1)
					(thickness 0.15)
				)
				(justify mirror)
			)
		)
		(sheetname "Com Express 7 MGMT")
		(sheetfile "com_express_7_mgmt.kicad_sch")
		(attr exclude_from_pos_files exclude_from_bom)
		(fp_circle
			(center 0 0)
			(end 0.475 0)
			(stroke
				(width 0.05)
				(type default)
			)
			(fill no)
			(layer "B.CrtYd")
		)
		(pad "1" smd circle
			(at 0 0)
			(size 0.75 0.75)
			(layers "B.Cu" "B.Mask")
			(net 352 "Net-(J12D-LPC_AD3{slash}ESPI_IO_3)")
			(pinfunction "1")
			(pintype "passive")
			(teardrops
				(best_length_ratio 0.4)
				(max_length 1)
				(best_width_ratio 0.9)
				(max_width 2)
				(curved_edges yes)
				(filter_ratio 0.9)
				(enabled yes)
				(allow_two_segments yes)
				(prefer_zone_connections yes)
			)
		)
	)
	(footprint "antmicro-footprints:R_0402_1005Metric"
		(layer "B.Cu")
		(at 126.09 138.06)
		(descr "Resistor SMD 0402")
		(tags "resistor SMD 0402")
		(property "Reference" "R297"
			(at -3.64 1.25 0)
			(layer "B.SilkS")
			(effects
				(font
					(size 0.7 0.7)
					(thickness 0.15)
				)
				(justify right bottom mirror)
			)
		)
		(property "Value" "R_10k_0402"
			(at -1.011843 -1.772047 0)
			(layer "B.Fab")
			(effects
				(font
					(size 0.7 0.7)
					(thickness 0.15)
				)
				(justify right bottom mirror)
			)
		)
		(property "Datasheet" "https://www.bourns.com/docs/product-datasheets/cr.pdf"
			(at 0 0 0)
			(layer "F.Fab")
			(hide yes)
			(effects
				(font
					(size 1.27 1.27)
					(thickness 0.15)
				)
			)
		)
		(property "Author" "Antmicro"
			(at 0 0 0)
			(layer "B.Fab")
			(hide yes)
			(effects
				(font
					(size 1 1)
					(thickness 0.15)
				)
				(justify mirror)
			)
		)
		(property "License" "Apache-2.0"
			(at 0 0 0)
			(layer "B.Fab")
			(hide yes)
			(effects
				(font
					(size 1 1)
					(thickness 0.15)
				)
				(justify mirror)
			)
		)
		(property "MPN" "CR0402-FX-1002GLF"
			(at 0 0 0)
			(layer "B.Fab")
			(hide yes)
			(effects
				(font
					(size 1 1)
					(thickness 0.15)
				)
				(justify mirror)
			)
		)
		(property "Manufacturer" "Bourns"
			(at 0 0 0)
			(layer "B.Fab")
			(hide yes)
			(effects
				(font
					(size 1 1)
					(thickness 0.15)
				)
				(justify mirror)
			)
		)
		(property "Public" "False"
			(at 0 0 0)
			(layer "B.Fab")
			(hide yes)
			(effects
				(font
					(size 1 1)
					(thickness 0.15)
				)
				(justify mirror)
			)
		)
		(property "Tolerance" "1%"
			(at 0 0 0)
			(layer "B.Fab")
			(hide yes)
			(effects
				(font
					(size 1 1)
					(thickness 0.15)
				)
				(justify mirror)
			)
		)
		(property "Val" "10k"
			(at 0 0 0)
			(layer "B.Fab")
			(hide yes)
			(effects
				(font
					(size 1 1)
					(thickness 0.15)
				)
				(justify mirror)
			)
		)
		(sheetname "KR to SFI #2")
		(sheetfile "kr_sfi.kicad_sch")
		(attr smd)
		(fp_rect
			(start -0.925 0.47)
			(end 0.925 -0.47)
			(stroke
				(width 0.05)
				(type default)
			)
			(fill no)
			(layer "B.CrtYd")
		)
		(fp_rect
			(start -0.5 0.25)
			(end 0.5 -0.25)
			(stroke
				(width 0.15)
				(type solid)
			)
			(fill no)
			(layer "B.Fab")
		)
		(pad "1" smd roundrect
			(at -0.48 0)
			(size 0.59 0.64)
			(layers "B.Cu" "B.Mask" "B.Paste")
			(roundrect_rratio 0.25)
			(net 1 "GND")
			(pintype "passive")
			(teardrops
				(best_length_ratio 0.2)
				(max_length 1)
				(best_width_ratio 0.9)
				(max_width 2)
				(curved_edges yes)
				(filter_ratio 0.9)
				(enabled yes)
				(allow_two_segments yes)
				(prefer_zone_connections yes)
			)
		)
		(pad "2" smd roundrect
			(at 0.48 0)
			(size 0.59 0.64)
			(layers "B.Cu" "B.Mask" "B.Paste")
			(roundrect_rratio 0.25)
			(net 677 "Net-(U45C-PRTAD1)")
			(pintype "passive")
			(teardrops
				(best_length_ratio 0.2)
				(max_length 1)
				(best_width_ratio 0.9)
				(max_width 2)
				(curved_edges yes)
				(filter_ratio 0.9)
				(enabled yes)
				(allow_two_segments yes)
				(prefer_zone_connections yes)
			)
		)
	)
	(footprint "antmicro-footprints:R_0402_1005Metric"
		(layer "B.Cu")
		(at 307.464999 121.96 90)
		(descr "Resistor SMD 0402")
		(tags "resistor SMD 0402")
		(property "Reference" "R93"
			(at -2.95 0.485001 90)
			(layer "B.SilkS")
			(effects
				(font
					(size 0.7 0.7)
					(thickness 0.15)
				)
				(justify right bottom mirror)
			)
		)
		(property "Value" "R_0R_0402"
			(at -1.011843 -1.772047 90)
			(layer "B.Fab")
			(effects
				(font
					(size 0.7 0.7)
					(thickness 0.15)
				)
				(justify right bottom mirror)
			)
		)
		(property "Datasheet" "https://industrial.panasonic.com/cdbs/www-data/pdf/RDA0000/AOA0000C301.pdf"
			(at 0 0 90)
			(layer "F.Fab")
			(hide yes)
			(effects
				(font
					(size 1.27 1.27)
					(thickness 0.15)
				)
			)
		)
		(property "Author" "Antmicro"
			(at 429.424999 -185.504999 0)
			(layer "B.Fab")
			(hide yes)
			(effects
				(font
					(size 1 1)
					(thickness 0.15)
				)
				(justify mirror)
			)
		)
		(property "Current" "1A"
			(at 429.424999 -185.504999 0)
			(layer "B.Fab")
			(hide yes)
			(effects
				(font
					(size 1 1)
					(thickness 0.15)
				)
				(justify mirror)
			)
		)
		(property "License" "Apache-2.0"
			(at 429.424999 -185.504999 0)
			(layer "B.Fab")
			(hide yes)
			(effects
				(font
					(size 1 1)
					(thickness 0.15)
				)
				(justify mirror)
			)
		)
		(property "MPN" "ERJ2GE0R00X"
			(at 429.424999 -185.504999 0)
			(layer "B.Fab")
			(hide yes)
			(effects
				(font
					(size 1 1)
					(thickness 0.15)
				)
				(justify mirror)
			)
		)
		(property "Manufacturer" "Panasonic"
			(at 429.424999 -185.504999 0)
			(layer "B.Fab")
			(hide yes)
			(effects
				(font
					(size 1 1)
					(thickness 0.15)
				)
				(justify mirror)
			)
		)
		(property "Public" "False"
			(at 429.424999 -185.504999 0)
			(layer "B.Fab")
			(hide yes)
			(effects
				(font
					(size 1 1)
					(thickness 0.15)
				)
				(justify mirror)
			)
		)
		(property "Tolerance" ""
			(at 429.424999 -185.504999 0)
			(layer "B.Fab")
			(hide yes)
			(effects
				(font
					(size 1 1)
					(thickness 0.15)
				)
				(justify mirror)
			)
		)
		(property "Val" "0R"
			(at 429.424999 -185.504999 0)
			(layer "B.Fab")
			(hide yes)
			(effects
				(font
					(size 1 1)
					(thickness 0.15)
				)
				(justify mirror)
			)
		)
		(sheetname "Power")
		(sheetfile "power.kicad_sch")
		(attr smd)
		(fp_rect
			(start -0.925 0.47)
			(end 0.925 -0.47)
			(stroke
				(width 0.05)
				(type default)
			)
			(fill no)
			(layer "B.CrtYd")
		)
		(fp_rect
			(start -0.5 0.25)
			(end 0.5 -0.25)
			(stroke
				(width 0.15)
				(type solid)
			)
			(fill no)
			(layer "B.Fab")
		)
		(pad "1" smd roundrect
			(at -0.48 0 90)
			(size 0.59 0.64)
			(layers "B.Cu" "B.Mask" "B.Paste")
			(roundrect_rratio 0.25)
			(net 78 "+1V8")
			(pintype "passive")
			(teardrops
				(best_length_ratio 0.2)
				(max_length 1)
				(best_width_ratio 0.9)
				(max_width 2)
				(curved_edges yes)
				(filter_ratio 0.9)
				(enabled yes)
				(allow_two_segments yes)
				(prefer_zone_connections yes)
			)
		)
		(pad "2" smd roundrect
			(at 0.48 0 90)
			(size 0.59 0.64)
			(layers "B.Cu" "B.Mask" "B.Paste")
			(roundrect_rratio 0.25)
			(net 577 "Net-(U18-EN)")
			(pintype "passive")
			(teardrops
				(best_length_ratio 0.2)
				(max_length 1)
				(best_width_ratio 0.9)
				(max_width 2)
				(curved_edges yes)
				(filter_ratio 0.9)
				(enabled yes)
				(allow_two_segments yes)
				(prefer_zone_connections yes)
			)
		)
	)
	(footprint "antmicro-footprints:R_0402_1005Metric"
		(layer "B.Cu")
		(at 144.25 136.06 180)
		(descr "Resistor SMD 0402")
		(tags "resistor SMD 0402")
		(property "Reference" "R259"
			(at -1.3 1.45 0)
			(layer "B.SilkS")
			(effects
				(font
					(size 0.7 0.7)
					(thickness 0.15)
				)
				(justify left bottom mirror)
			)
		)
		(property "Value" "R_10k_0402"
			(at -1.011843 -1.772047 0)
			(layer "B.Fab")
			(effects
				(font
					(size 0.7 0.7)
					(thickness 0.15)
				)
				(justify left bottom mirror)
			)
		)
		(property "Datasheet" "https://www.bourns.com/docs/product-datasheets/cr.pdf"
			(at 0 0 180)
			(layer "F.Fab")
			(hide yes)
			(effects
				(font
					(size 1.27 1.27)
					(thickness 0.15)
				)
			)
		)
		(property "Author" "Antmicro"
			(at 288.5 272.12 0)
			(layer "B.Fab")
			(hide yes)
			(effects
				(font
					(size 1 1)
					(thickness 0.15)
				)
				(justify mirror)
			)
		)
		(property "License" "Apache-2.0"
			(at 288.5 272.12 0)
			(layer "B.Fab")
			(hide yes)
			(effects
				(font
					(size 1 1)
					(thickness 0.15)
				)
				(justify mirror)
			)
		)
		(property "MPN" "CR0402-FX-1002GLF"
			(at 288.5 272.12 0)
			(layer "B.Fab")
			(hide yes)
			(effects
				(font
					(size 1 1)
					(thickness 0.15)
				)
				(justify mirror)
			)
		)
		(property "Manufacturer" "Bourns"
			(at 288.5 272.12 0)
			(layer "B.Fab")
			(hide yes)
			(effects
				(font
					(size 1 1)
					(thickness 0.15)
				)
				(justify mirror)
			)
		)
		(property "Public" "False"
			(at 288.5 272.12 0)
			(layer "B.Fab")
			(hide yes)
			(effects
				(font
					(size 1 1)
					(thickness 0.15)
				)
				(justify mirror)
			)
		)
		(property "Tolerance" "1%"
			(at 288.5 272.12 0)
			(layer "B.Fab")
			(hide yes)
			(effects
				(font
					(size 1 1)
					(thickness 0.15)
				)
				(justify mirror)
			)
		)
		(property "Val" "10k"
			(at 288.5 272.12 0)
			(layer "B.Fab")
			(hide yes)
			(effects
				(font
					(size 1 1)
					(thickness 0.15)
				)
				(justify mirror)
			)
		)
		(sheetname "KR to SFI #1")
		(sheetfile "kr_sfi.kicad_sch")
		(attr smd)
		(fp_rect
			(start -0.925 0.47)
			(end 0.925 -0.47)
			(stroke
				(width 0.05)
				(type default)
			)
			(fill no)
			(layer "B.CrtYd")
		)
		(fp_rect
			(start -0.5 0.25)
			(end 0.5 -0.25)
			(stroke
				(width 0.15)
				(type solid)
			)
			(fill no)
			(layer "B.Fab")
		)
		(pad "1" smd roundrect
			(at -0.48 0 180)
			(size 0.59 0.64)
			(layers "B.Cu" "B.Mask" "B.Paste")
			(roundrect_rratio 0.25)
			(net 141 "/2xSFP+/KR to SFI #1/~{RESET}")
			(pintype "passive")
			(teardrops
				(best_length_ratio 0.2)
				(max_length 1)
				(best_width_ratio 0.9)
				(max_width 2)
				(curved_edges yes)
				(filter_ratio 0.9)
				(enabled yes)
				(allow_two_segments yes)
				(prefer_zone_connections yes)
			)
		)
		(pad "2" smd roundrect
			(at 0.48 0 180)
			(size 0.59 0.64)
			(layers "B.Cu" "B.Mask" "B.Paste")
			(roundrect_rratio 0.25)
			(net 78 "+1V8")
			(pintype "passive")
			(teardrops
				(best_length_ratio 0.2)
				(max_length 1)
				(best_width_ratio 0.9)
				(max_width 2)
				(curved_edges yes)
				(filter_ratio 0.9)
				(enabled yes)
				(allow_two_segments yes)
				(prefer_zone_connections yes)
			)
		)
	)
	(footprint "antmicro-footprints:C_0402_1005Metric"
		(layer "B.Cu")
		(at 149.95 134.86)
		(descr "Capacitor SMD 0402")
		(tags "capacitor SMD 0402")
		(property "Reference" "C167"
			(at -3.1 -4.85 0)
			(layer "B.SilkS")
			(effects
				(font
					(size 0.7 0.7)
					(thickness 0.15)
				)
				(justify right bottom mirror)
			)
		)
		(property "Value" "C_100n_0402"
			(at -1.022927 -2.155213 0)
			(layer "B.Fab")
			(effects
				(font
					(size 0.7 0.7)
					(thickness 0.15)
				)
				(justify right bottom mirror)
			)
		)
		(property "Datasheet" "https://www.murata.com/products/productdetail?partno=GRM155R61H104KE14%23"
			(at 0 0 0)
			(layer "F.Fab")
			(hide yes)
			(effects
				(font
					(size 1.27 1.27)
					(thickness 0.15)
				)
			)
		)
		(property "Author" "Antmicro"
			(at 0 0 0)
			(layer "B.Fab")
			(hide yes)
			(effects
				(font
					(size 1 1)
					(thickness 0.15)
				)
				(justify mirror)
			)
		)
		(property "Dielectric" "X5R"
			(at 0 0 0)
			(layer "B.Fab")
			(hide yes)
			(effects
				(font
					(size 1 1)
					(thickness 0.15)
				)
				(justify mirror)
			)
		)
		(property "License" "Apache-2.0"
			(at 0 0 0)
			(layer "B.Fab")
			(hide yes)
			(effects
				(font
					(size 1 1)
					(thickness 0.15)
				)
				(justify mirror)
			)
		)
		(property "MPN" "GRM155R61H104KE14D"
			(at 0 0 0)
			(layer "B.Fab")
			(hide yes)
			(effects
				(font
					(size 1 1)
					(thickness 0.15)
				)
				(justify mirror)
			)
		)
		(property "Manufacturer" "Murata"
			(at 0 0 0)
			(layer "B.Fab")
			(hide yes)
			(effects
				(font
					(size 1 1)
					(thickness 0.15)
				)
				(justify mirror)
			)
		)
		(property "Public" "False"
			(at 0 0 0)
			(layer "B.Fab")
			(hide yes)
			(effects
				(font
					(size 1 1)
					(thickness 0.15)
				)
				(justify mirror)
			)
		)
		(property "Val" "100n"
			(at 0 0 0)
			(layer "B.Fab")
			(hide yes)
			(effects
				(font
					(size 1 1)
					(thickness 0.15)
				)
				(justify mirror)
			)
		)
		(property "Voltage" "50V"
			(at 0 0 0)
			(layer "B.Fab")
			(hide yes)
			(effects
				(font
					(size 1 1)
					(thickness 0.15)
				)
				(justify mirror)
			)
		)
		(sheetname "KR to SFI #1")
		(sheetfile "kr_sfi.kicad_sch")
		(attr smd)
		(fp_rect
			(start -0.925 0.47)
			(end 0.925 -0.47)
			(stroke
				(width 0.05)
				(type default)
			)
			(fill no)
			(layer "B.CrtYd")
		)
		(fp_line
			(start -0.494 -0.248)
			(end 0.504 -0.248)
			(stroke
				(width 0.15)
				(type solid)
			)
			(layer "B.Fab")
		)
		(fp_line
			(start -0.494 0.25)
			(end -0.494 -0.248)
			(stroke
				(width 0.15)
				(type solid)
			)
			(layer "B.Fab")
		)
		(fp_line
			(start 0.504 -0.248)
			(end 0.504 0.25)
			(stroke
				(width 0.15)
				(type solid)
			)
			(layer "B.Fab")
		)
		(fp_line
			(start 0.504 0.25)
			(end -0.494 0.25)
			(stroke
				(width 0.15)
				(type solid)
			)
			(layer "B.Fab")
		)
		(pad "1" smd roundrect
			(at -0.48 0)
			(size 0.59 0.64)
			(layers "B.Cu" "B.Mask" "B.Paste")
			(roundrect_rratio 0.25)
			(net 1 "GND")
			(pintype "passive")
			(teardrops
				(best_length_ratio 0.2)
				(max_length 1)
				(best_width_ratio 0.9)
				(max_width 2)
				(curved_edges yes)
				(filter_ratio 0.9)
				(enabled yes)
				(allow_two_segments yes)
				(prefer_zone_connections yes)
			)
		)
		(pad "2" smd roundrect
			(at 0.48 0)
			(size 0.59 0.64)
			(layers "B.Cu" "B.Mask" "B.Paste")
			(roundrect_rratio 0.25)
			(net 74 "+1V0")
			(pintype "passive")
			(teardrops
				(best_length_ratio 0.2)
				(max_length 1)
				(best_width_ratio 0.9)
				(max_width 2)
				(curved_edges yes)
				(filter_ratio 0.9)
				(enabled yes)
				(allow_two_segments yes)
				(prefer_zone_connections yes)
			)
		)
	)
	(footprint "antmicro-footprints:C_0402_1005Metric"
		(layer "B.Cu")
		(at 196.00804 142.248957 135)
		(descr "Capacitor SMD 0402")
		(tags "capacitor SMD 0402")
		(property "Reference" "C129"
			(at -3.530586 -0.359976 135)
			(layer "B.SilkS")
			(effects
				(font
					(size 0.7 0.7)
					(thickness 0.15)
				)
				(justify right bottom mirror)
			)
		)
		(property "Value" "C_220n_0402"
			(at -1.022927 -2.155213 135)
			(layer "B.Fab")
			(effects
				(font
					(size 0.7 0.7)
					(thickness 0.15)
				)
				(justify right bottom mirror)
			)
		)
		(property "Datasheet" "https://www.yageo.com/en/Chart/Download/pdf/CC0402KRX5R6BB224"
			(at 0 0 135)
			(layer "F.Fab")
			(hide yes)
			(effects
				(font
					(size 1.27 1.27)
					(thickness 0.15)
				)
			)
		)
		(property "Author" "Antmicro"
			(at 340.300001 -43.5 45)
			(layer "B.Fab")
			(hide yes)
			(effects
				(font
					(size 1 1)
					(thickness 0.15)
				)
				(justify mirror)
			)
		)
		(property "Dielectric" ""
			(at 340.300001 -43.5 45)
			(layer "B.Fab")
			(hide yes)
			(effects
				(font
					(size 1 1)
					(thickness 0.15)
				)
				(justify mirror)
			)
		)
		(property "License" "Apache-2.0"
			(at 340.300001 -43.5 45)
			(layer "B.Fab")
			(hide yes)
			(effects
				(font
					(size 1 1)
					(thickness 0.15)
				)
				(justify mirror)
			)
		)
		(property "MPN" "CC0402KRX5R6BB224"
			(at 340.300001 -43.5 45)
			(layer "B.Fab")
			(hide yes)
			(effects
				(font
					(size 1 1)
					(thickness 0.15)
				)
				(justify mirror)
			)
		)
		(property "Manufacturer" "YAGEO"
			(at 340.300001 -43.5 45)
			(layer "B.Fab")
			(hide yes)
			(effects
				(font
					(size 1 1)
					(thickness 0.15)
				)
				(justify mirror)
			)
		)
		(property "Public" "False"
			(at 340.300001 -43.5 45)
			(layer "B.Fab")
			(hide yes)
			(effects
				(font
					(size 1 1)
					(thickness 0.15)
				)
				(justify mirror)
			)
		)
		(property "Val" "220n"
			(at 340.300001 -43.5 45)
			(layer "B.Fab")
			(hide yes)
			(effects
				(font
					(size 1 1)
					(thickness 0.15)
				)
				(justify mirror)
			)
		)
		(property "Voltage" ""
			(at 340.300001 -43.5 45)
			(layer "B.Fab")
			(hide yes)
			(effects
				(font
					(size 1 1)
					(thickness 0.15)
				)
				(justify mirror)
			)
		)
		(sheetname "PCIe redriver")
		(sheetfile "pcie_redriver.kicad_sch")
		(attr smd)
		(fp_poly
			(pts
				(xy -0.925 0.47) (xy 0.925 0.47) (xy 0.925 -0.47) (xy -0.925 -0.47)
			)
			(stroke
				(width 0.05)
				(type default)
			)
			(fill no)
			(layer "B.CrtYd")
		)
		(fp_line
			(start 0.504 -0.248)
			(end 0.504 0.25)
			(stroke
				(width 0.15)
				(type solid)
			)
			(layer "B.Fab")
		)
		(fp_line
			(start 0.504 0.25)
			(end -0.494 0.25)
			(stroke
				(width 0.15)
				(type solid)
			)
			(layer "B.Fab")
		)
		(fp_line
			(start -0.494 -0.248)
			(end 0.504 -0.248)
			(stroke
				(width 0.15)
				(type solid)
			)
			(layer "B.Fab")
		)
		(fp_line
			(start -0.494 0.25)
			(end -0.494 -0.248)
			(stroke
				(width 0.15)
				(type solid)
			)
			(layer "B.Fab")
		)
		(pad "1" smd roundrect
			(at -0.48 0 135)
			(size 0.59 0.64)
			(layers "B.Cu" "B.Mask" "B.Paste")
			(roundrect_rratio 0.25)
			(net 210 "/Com Express 7 Interfaces/PCIe_{B1x4}.RX3+")
			(pintype "passive")
			(teardrops
				(best_length_ratio 0.2)
				(max_length 1)
				(best_width_ratio 0.9)
				(max_width 2)
				(curved_edges yes)
				(filter_ratio 0.9)
				(enabled yes)
				(allow_two_segments yes)
				(prefer_zone_connections yes)
			)
		)
		(pad "2" smd roundrect
			(at 0.48 0 135)
			(size 0.59 0.64)
			(layers "B.Cu" "B.Mask" "B.Paste")
			(roundrect_rratio 0.25)
			(net 960 "/PCIe redriver/PCIe_{I}_C.RX3+")
			(pintype "passive")
			(teardrops
				(best_length_ratio 0.2)
				(max_length 1)
				(best_width_ratio 0.9)
				(max_width 2)
				(curved_edges yes)
				(filter_ratio 0.9)
				(enabled yes)
				(allow_two_segments yes)
				(prefer_zone_connections yes)
			)
		)
	)
)
